(kicad_pcb
	(version 20260206)
	(generator "pcbnew")
	(generator_version "10.0")
	(general
		(thickness 1.6)
		(legacy_teardrops no)
	)
	(paper "A4")
	(title_block
		(title "Bryce Canyon_R.DPB_16317-1_OCP.brd")
		(comment 1 "Bryce Canyon / footprints 1577-1584 of 2099")
	)
	(layers
		(0 "F.Cu" signal "TOP")
		(4 "In1.Cu" signal "L2GND")
		(6 "In2.Cu" signal "L3")
		(8 "In3.Cu" signal "L4VCC")
		(10 "In4.Cu" signal "L5VCC")
		(12 "In5.Cu" signal "L6")
		(14 "In6.Cu" signal "L7GND")
		(2 "B.Cu" signal "BOTTOM")
		(9 "F.Adhes" user "F.Adhesive")
		(11 "B.Adhes" user "B.Adhesive")
		(13 "F.Paste" user "Package Geometry/Pastemask Top")
		(15 "B.Paste" user "Package Geometry/Pastemask Bottom")
		(5 "F.SilkS" user "Ref Des/Silkscreen Top")
		(7 "B.SilkS" user "Ref Des/Silkscreen Bottom")
		(1 "F.Mask" user "Board Geometry/Soldermask Top")
		(3 "B.Mask" user "Board Geometry/Soldermask Bottom")
		(17 "Dwgs.User" user "User.Drawings")
		(19 "Cmts.User" user "User.Comments")
		(21 "Eco1.User" user "User.Eco1")
		(23 "Eco2.User" user "User.Eco2")
		(25 "Edge.Cuts" user "Board Geometry/Outline")
		(27 "Margin" user)
		(31 "F.CrtYd" user "Package Geometry/Place Bound Top")
		(29 "B.CrtYd" user "Package Geometry/Place Bound Bottom")
		(35 "F.Fab" user "Ref Des/Assembly Top")
		(33 "B.Fab" user "Ref Des/Assembly Bottom")
	)
	(footprint ""
		(layer "F.Cu")
		(at 233.1212 -194.2592 -90)
		(property "Reference" "R75"
			(at 0 0 270)
			(layer "F.SilkS")
			(hide yes)
			(effects
				(font
					(size 1.27 1.27)
				)
			)
		)
		(property "Value" "0R2J-2-GP"
			(at 0.064008 -3.993896 270)
			(unlocked yes)
			(layer "F.Fab")
			(hide yes)
			(effects
				(font
					(size 1.016 1.016)
					(thickness 0.1524)
				)
			)
		)
		(property "Device Type" "R402H16"
			(at 0.064008 -5.517896 270)
			(unlocked yes)
			(layer "F.Fab")
			(hide yes)
			(effects
				(font
					(size 1.016 1.016)
					(thickness 0.1524)
				)
			)
		)
		(duplicate_pad_numbers_are_jumpers no)
		(fp_line
			(start -0.508 -0.9398)
			(end -0.508 0.9398)
			(stroke
				(width 0.1524)
				(type default)
			)
			(layer "F.SilkS")
		)
		(fp_line
			(start 0.508 -0.9398)
			(end -0.508 -0.9398)
			(stroke
				(width 0.1524)
				(type default)
			)
			(layer "F.SilkS")
		)
		(fp_rect
			(start -0.508 0.9398)
			(end 0.508 -0.9398)
			(stroke
				(width 0)
				(type default)
			)
			(fill no)
			(layer "F.CrtYd")
		)
		(fp_rect
			(start -0.508 0.9398)
			(end 0.508 -0.9398)
			(stroke
				(width 0)
				(type default)
			)
			(fill no)
			(layer "F.Fab")
		)
		(pad "1" smd custom
			(at 0 -0.4445 270)
			(size 0.1397 0.1397)
			(layers "F.Cu" "F.Mask" "F.Paste")
			(net "IO_EXP2_SDA")
			(options
				(clearance outline)
				(anchor circle)
			)
			(primitives
				(gr_poly
					(pts
						(arc
							(start -0.1778 -0.2794)
							(mid -0.249642 -0.249642)
							(end -0.2794 -0.1778)
						)
						(arc
							(start -0.2794 0.1778)
							(mid -0.249642 0.249642)
							(end -0.1778 0.2794)
						)
						(arc
							(start 0.1778 0.2794)
							(mid 0.249642 0.249642)
							(end 0.2794 0.1778)
						)
						(arc
							(start 0.2794 -0.1778)
							(mid 0.249642 -0.249642)
							(end 0.1778 -0.2794)
						)
					)
					(width 0)
					(fill yes)
				)
			)
		)
		(pad "2" smd custom
			(at 0 0.4445 270)
			(size 0.1397 0.1397)
			(layers "F.Cu" "F.Mask" "F.Paste")
			(net "I2C_DRIVE_B_PWR_SDA")
			(options
				(clearance outline)
				(anchor circle)
			)
			(primitives
				(gr_poly
					(pts
						(arc
							(start -0.1778 -0.2794)
							(mid -0.249642 -0.249642)
							(end -0.2794 -0.1778)
						)
						(arc
							(start -0.2794 0.1778)
							(mid -0.249642 0.249642)
							(end -0.1778 0.2794)
						)
						(arc
							(start 0.1778 0.2794)
							(mid 0.249642 0.249642)
							(end 0.2794 0.1778)
						)
						(arc
							(start 0.2794 -0.1778)
							(mid 0.249642 -0.249642)
							(end 0.1778 -0.2794)
						)
					)
					(width 0)
					(fill yes)
				)
			)
		)
	)
	(footprint ""
		(layer "F.Cu")
		(at 431.927 -133.858 90)
		(property "Reference" "D21"
			(at 0 0 90)
			(layer "F.SilkS")
			(hide yes)
			(effects
				(font
					(size 1.27 1.27)
				)
			)
		)
		(property "Value" "RB551V30-GP"
			(at 0 -6.7818 90)
			(unlocked yes)
			(layer "F.Fab")
			(hide yes)
			(effects
				(font
					(size 1.016 1.016)
					(thickness 0.1524)
				)
			)
		)
		(property "Device Type" "SOD323AKH38"
			(at 0 -8.6868 90)
			(unlocked yes)
			(layer "F.Fab")
			(hide yes)
			(effects
				(font
					(size 1.016 1.016)
					(thickness 0.1524)
				)
			)
		)
		(duplicate_pad_numbers_are_jumpers no)
		(fp_line
			(start 0.889 -1.9304)
			(end 0.889 2.159)
			(stroke
				(width 0.1524)
				(type default)
			)
			(layer "F.SilkS")
		)
		(fp_line
			(start -0.889 -1.9304)
			(end 0.889 -1.9304)
			(stroke
				(width 0.1524)
				(type default)
			)
			(layer "F.SilkS")
		)
		(fp_line
			(start 0.762 2.0574)
			(end -0.762 2.0574)
			(stroke
				(width 0.508)
				(type default)
			)
			(layer "F.SilkS")
		)
		(fp_line
			(start 0.889 2.159)
			(end -0.889 2.159)
			(stroke
				(width 0.1524)
				(type default)
			)
			(layer "F.SilkS")
		)
		(fp_line
			(start -0.889 2.159)
			(end -0.889 -1.9304)
			(stroke
				(width 0.1524)
				(type default)
			)
			(layer "F.SilkS")
		)
		(fp_rect
			(start -1.016 2.3114)
			(end 1.016 -2.0066)
			(stroke
				(width 0)
				(type default)
			)
			(fill no)
			(layer "F.CrtYd")
		)
		(fp_poly
			(pts
				(xy -1.016 -2.0066) (xy 1.016 -2.0066) (xy 1.016 2.3114) (xy -1.016 2.3114)
			)
			(stroke
				(width 0)
				(type default)
			)
			(fill no)
			(layer "F.Fab")
		)
		(pad "A" smd rect
			(at 0 -1.143 90)
			(size 0.5588 1.016)
			(layers "F.Cu" "F.Mask" "F.Paste")
			(net "SW_HDD_R21")
		)
		(pad "K" smd rect
			(at 0 1.143 90)
			(size 0.5588 1.016)
			(layers "F.Cu" "F.Mask" "F.Paste")
			(net "SW_HDD_N21")
		)
	)
	(footprint ""
		(layer "F.Cu")
		(at 29.177996 -373.888 -90)
		(property "Reference" "Q215"
			(at 0 0 270)
			(layer "F.SilkS")
			(hide yes)
			(effects
				(font
					(size 1.27 1.27)
				)
			)
		)
		(property "Value" "2N7002KDW-GP"
			(at -2.3622 -8.2042 270)
			(unlocked yes)
			(layer "F.Fab")
			(hide yes)
			(effects
				(font
					(size 1.016 1.016)
					(thickness 0.1524)
				)
			)
		)
		(property "Device Type" "SOT-363H44"
			(at -2.3622 -10.1092 270)
			(unlocked yes)
			(layer "F.Fab")
			(hide yes)
			(effects
				(font
					(size 1.016 1.016)
					(thickness 0.1524)
				)
			)
		)
		(duplicate_pad_numbers_are_jumpers no)
		(fp_line
			(start -1.4478 1.7018)
			(end 1.4478 1.7018)
			(stroke
				(width 0.1524)
				(type default)
			)
			(layer "F.SilkS")
		)
		(fp_line
			(start 1.4478 1.7018)
			(end 1.4478 -1.7018)
			(stroke
				(width 0.1524)
				(type default)
			)
			(layer "F.SilkS")
		)
		(fp_line
			(start -1.27 1.524)
			(end -1.27 0.6604)
			(stroke
				(width 0.4826)
				(type default)
			)
			(layer "F.SilkS")
		)
		(fp_line
			(start -1.4478 -1.7018)
			(end -1.4478 1.7018)
			(stroke
				(width 0.1524)
				(type default)
			)
			(layer "F.SilkS")
		)
		(fp_line
			(start 1.4478 -1.7018)
			(end -1.4478 -1.7018)
			(stroke
				(width 0.1524)
				(type default)
			)
			(layer "F.SilkS")
		)
		(fp_poly
			(pts
				(xy -1.524 -1.778) (xy 1.524 -1.778) (xy 1.524 1.778) (xy -1.524 1.778)
			)
			(stroke
				(width 0)
				(type default)
			)
			(fill no)
			(layer "F.CrtYd")
		)
		(fp_poly
			(pts
				(xy -1.524 -1.778) (xy 1.524 -1.778) (xy 1.524 1.778) (xy -1.524 1.778)
			)
			(stroke
				(width 0)
				(type default)
			)
			(fill no)
			(layer "F.Fab")
		)
		(pad "1" smd rect
			(at -0.65024 0.9398 270)
			(size 0.4064 1.016)
			(layers "F.Cu" "F.Mask" "F.Paste")
			(net "GND")
		)
		(pad "2" smd rect
			(at 0 0.9398 270)
			(size 0.4064 1.016)
			(layers "F.Cu" "F.Mask" "F.Paste")
			(net "FAN_LED0_D")
		)
		(pad "3" smd rect
			(at 0.65024 0.9398 270)
			(size 0.4064 1.016)
			(layers "F.Cu" "F.Mask" "F.Paste")
			(net "FAN_LED0_D")
		)
		(pad "4" smd rect
			(at 0.65024 -0.9398 270)
			(size 0.4064 1.016)
			(layers "F.Cu" "F.Mask" "F.Paste")
			(net "GND")
		)
		(pad "5" smd rect
			(at 0 -0.9398 270)
			(size 0.4064 1.016)
			(layers "F.Cu" "F.Mask" "F.Paste")
			(net "FAN_LED0")
		)
		(pad "6" smd rect
			(at -0.65024 -0.9398 270)
			(size 0.4064 1.016)
			(layers "F.Cu" "F.Mask" "F.Paste")
			(net "FAN_LED0_D2")
		)
	)
	(footprint ""
		(layer "F.Cu")
		(at 20.066 -262.001 -90)
		(property "Reference" "C499"
			(at 0 0 270)
			(layer "F.SilkS")
			(hide yes)
			(effects
				(font
					(size 1.27 1.27)
				)
			)
		)
		(property "Value" "SC10U16V6KX-2GP"
			(at -0.0762 -5.1308 270)
			(unlocked yes)
			(layer "F.Fab")
			(hide yes)
			(effects
				(font
					(size 1.016 1.016)
					(thickness 0.1524)
				)
			)
		)
		(property "Device Type" "C1206H71"
			(at -0.127 -6.6548 270)
			(unlocked yes)
			(layer "F.Fab")
			(hide yes)
			(effects
				(font
					(size 1.016 1.016)
					(thickness 0.1524)
				)
			)
		)
		(duplicate_pad_numbers_are_jumpers no)
		(fp_line
			(start -1.016 2.2352)
			(end -1.016 0.8382)
			(stroke
				(width 0.1524)
				(type default)
			)
			(layer "F.SilkS")
		)
		(fp_line
			(start 1.016 2.2352)
			(end -1.016 2.2352)
			(stroke
				(width 0.1524)
				(type default)
			)
			(layer "F.SilkS")
		)
		(fp_line
			(start 1.016 0.8382)
			(end 1.016 2.2352)
			(stroke
				(width 0.1524)
				(type default)
			)
			(layer "F.SilkS")
		)
		(fp_line
			(start -1.016 -0.8382)
			(end -1.016 -2.2352)
			(stroke
				(width 0.1524)
				(type default)
			)
			(layer "F.SilkS")
		)
		(fp_line
			(start -1.016 -2.2352)
			(end 1.016 -2.2352)
			(stroke
				(width 0.1524)
				(type default)
			)
			(layer "F.SilkS")
		)
		(fp_line
			(start 1.016 -2.2352)
			(end 1.016 -0.8382)
			(stroke
				(width 0.1524)
				(type default)
			)
			(layer "F.SilkS")
		)
		(fp_rect
			(start -1.0922 2.3114)
			(end 1.0922 -2.3114)
			(stroke
				(width 0)
				(type default)
			)
			(fill no)
			(layer "F.CrtYd")
		)
		(fp_poly
			(pts
				(xy 1.0922 -2.3114) (xy 1.0922 2.3114) (xy -1.0922 2.3114) (xy -1.0922 -2.3114)
			)
			(stroke
				(width 0)
				(type default)
			)
			(fill no)
			(layer "F.Fab")
		)
		(pad "1" smd rect
			(at 0 -1.397 270)
			(size 1.651 1.27)
			(layers "F.Cu" "F.Mask" "F.Paste")
			(net "P5V_HDD0")
		)
		(pad "2" smd rect
			(at 0 1.397 270)
			(size 1.651 1.27)
			(layers "F.Cu" "F.Mask" "F.Paste")
			(net "GND")
		)
	)
	(footprint ""
		(layer "F.Cu")
		(at 44.290996 -357.2256)
		(property "Reference" "D49"
			(at 0 0 0)
			(layer "F.SilkS")
			(hide yes)
			(effects
				(font
					(size 1.27 1.27)
				)
			)
		)
		(property "Value" "RB551V30-GP"
			(at 0 -6.7818 0)
			(unlocked yes)
			(layer "F.Fab")
			(hide yes)
			(effects
				(font
					(size 1.016 1.016)
					(thickness 0.1524)
				)
			)
		)
		(property "Device Type" "SOD323AKH38"
			(at 0 -8.6868 0)
			(unlocked yes)
			(layer "F.Fab")
			(hide yes)
			(effects
				(font
					(size 1.016 1.016)
					(thickness 0.1524)
				)
			)
		)
		(duplicate_pad_numbers_are_jumpers no)
		(fp_line
			(start -0.889 -1.9304)
			(end 0.889 -1.9304)
			(stroke
				(width 0.1524)
				(type default)
			)
			(layer "F.SilkS")
		)
		(fp_line
			(start -0.889 2.159)
			(end -0.889 -1.9304)
			(stroke
				(width 0.1524)
				(type default)
			)
			(layer "F.SilkS")
		)
		(fp_line
			(start 0.762 2.0574)
			(end -0.762 2.0574)
			(stroke
				(width 0.508)
				(type default)
			)
			(layer "F.SilkS")
		)
		(fp_line
			(start 0.889 -1.9304)
			(end 0.889 2.159)
			(stroke
				(width 0.1524)
				(type default)
			)
			(layer "F.SilkS")
		)
		(fp_line
			(start 0.889 2.159)
			(end -0.889 2.159)
			(stroke
				(width 0.1524)
				(type default)
			)
			(layer "F.SilkS")
		)
		(fp_rect
			(start -1.016 2.3114)
			(end 1.016 -2.0066)
			(stroke
				(width 0)
				(type default)
			)
			(fill no)
			(layer "F.CrtYd")
		)
		(fp_poly
			(pts
				(xy -1.016 -2.0066) (xy 1.016 -2.0066) (xy 1.016 2.3114) (xy -1.016 2.3114)
			)
			(stroke
				(width 0)
				(type default)
			)
			(fill no)
			(layer "F.Fab")
		)
		(pad "A" smd rect
			(at 0 -1.143)
			(size 0.5588 1.016)
			(layers "F.Cu" "F.Mask" "F.Paste")
			(net "GATE_FAN0")
		)
		(pad "K" smd rect
			(at 0 1.143)
			(size 0.5588 1.016)
			(layers "F.Cu" "F.Mask" "F.Paste")
			(net "GATE_FAN0_R")
		)
	)
	(footprint ""
		(layer "F.Cu")
		(at 368.3 -148.082)
		(property "Reference" "Q90"
			(at 0 0 0)
			(layer "F.SilkS")
			(hide yes)
			(effects
				(font
					(size 1.27 1.27)
				)
			)
		)
		(property "Value" "AO4407AL-GP"
			(at -3.707384 -1.5367 0)
			(unlocked yes)
			(layer "F.Fab")
			(hide yes)
			(effects
				(font
					(size 1.016 1.016)
					(thickness 0.1524)
				)
			)
		)
		(property "Device Type" "SOIC8H69"
			(at -3.707384 -3.0607 0)
			(unlocked yes)
			(layer "F.Fab")
			(hide yes)
			(effects
				(font
					(size 1.016 1.016)
					(thickness 0.1524)
				)
			)
		)
		(duplicate_pad_numbers_are_jumpers no)
		(fp_line
			(start -2.7432 -1.4224)
			(end -2.7432 1.4224)
			(stroke
				(width 0.1524)
				(type default)
			)
			(layer "F.SilkS")
		)
		(fp_line
			(start -2.7432 1.4224)
			(end -2.6416 1.4224)
			(stroke
				(width 0.1524)
				(type default)
			)
			(layer "F.SilkS")
		)
		(fp_line
			(start -2.7432 1.4224)
			(end 2.1336 1.4224)
			(stroke
				(width 0.1524)
				(type default)
			)
			(layer "F.SilkS")
		)
		(fp_line
			(start -2.7178 -0.508)
			(end -2.1844 -0.0508)
			(stroke
				(width 0.1524)
				(type default)
			)
			(layer "F.SilkS")
		)
		(fp_line
			(start -2.6289 3.4417)
			(end -2.6289 1.4732)
			(stroke
				(width 0.381)
				(type default)
			)
			(layer "F.SilkS")
		)
		(fp_line
			(start -2.1844 -0.0508)
			(end -2.7178 0.508)
			(stroke
				(width 0.1524)
				(type default)
			)
			(layer "F.SilkS")
		)
		(fp_line
			(start 2.1336 -1.4224)
			(end -2.7432 -1.4224)
			(stroke
				(width 0.1524)
				(type default)
			)
			(layer "F.SilkS")
		)
		(fp_line
			(start 2.1336 1.4224)
			(end 2.1336 -1.4224)
			(stroke
				(width 0.1524)
				(type default)
			)
			(layer "F.SilkS")
		)
		(fp_poly
			(pts
				(xy -2.2098 -1.4224) (xy -2.2098 1.4224) (xy 2.2098 1.4224) (xy 2.2098 -1.4224)
			)
			(stroke
				(width 0)
				(type default)
			)
			(fill yes)
			(layer "F.SilkS")
		)
		(fp_rect
			(start -2.450084 2.999994)
			(end 2.450084 -2.999994)
			(stroke
				(width 0)
				(type default)
			)
			(fill no)
			(layer "F.CrtYd")
		)
		(fp_poly
			(pts
				(xy -2.8194 3.6322) (xy -2.8194 -3.6322) (xy 2.8194 -3.6322) (xy 2.8194 1.18364) (xy 2.450084 1.18364)
				(xy 2.450084 -2.999994) (xy -2.450084 -2.999994) (xy -2.450084 2.999994) (xy 2.450084 2.999994)
				(xy 2.450084 1.18618) (xy 2.8194 1.18618) (xy 2.8194 3.6322)
			)
			(stroke
				(width 0)
				(type default)
			)
			(fill no)
			(layer "F.CrtYd")
		)
		(fp_rect
			(start -2.8194 3.6322)
			(end 2.8194 -3.6322)
			(stroke
				(width 0)
				(type default)
			)
			(fill no)
			(layer "F.Fab")
		)
		(pad "1" smd rect
			(at -1.905 2.54)
			(size 0.635 1.651)
			(layers "F.Cu" "F.Mask" "F.Paste")
			(net "P12V_B")
		)
		(pad "2" smd rect
			(at -0.635 2.54)
			(size 0.635 1.651)
			(layers "F.Cu" "F.Mask" "F.Paste")
			(net "P12V_B")
		)
		(pad "3" smd rect
			(at 0.635 2.54)
			(size 0.635 1.651)
			(layers "F.Cu" "F.Mask" "F.Paste")
			(net "P12V_B")
		)
		(pad "4" smd rect
			(at 1.905 2.54)
			(size 0.635 1.651)
			(layers "F.Cu" "F.Mask" "F.Paste")
			(net "SW_HDD_N19")
		)
		(pad "5" smd rect
			(at 1.905 -2.54)
			(size 0.635 1.651)
			(layers "F.Cu" "F.Mask" "F.Paste")
			(net "P12V_HDD19")
		)
		(pad "6" smd rect
			(at 0.635 -2.54)
			(size 0.635 1.651)
			(layers "F.Cu" "F.Mask" "F.Paste")
			(net "P12V_HDD19")
		)
		(pad "7" smd rect
			(at -0.635 -2.54)
			(size 0.635 1.651)
			(layers "F.Cu" "F.Mask" "F.Paste")
			(net "P12V_HDD19")
		)
		(pad "8" smd rect
			(at -1.905 -2.54)
			(size 0.635 1.651)
			(layers "F.Cu" "F.Mask" "F.Paste")
			(net "P12V_HDD19")
		)
	)
	(footprint ""
		(layer "F.Cu")
		(at 331.47 -274.955 180)
		(property "Reference" "C112"
			(at 0 0 180)
			(layer "F.SilkS")
			(hide yes)
			(effects
				(font
					(size 1.27 1.27)
				)
			)
		)
		(property "Value" "SC4D7U25V5KX-1-GP"
			(at -0.0762 -6.1214 180)
			(unlocked yes)
			(layer "F.Fab")
			(hide yes)
			(effects
				(font
					(size 1.016 1.016)
					(thickness 0.1524)
				)
			)
		)
		(property "Device Type" "C805H58"
			(at -0.0762 -8.1534 180)
			(unlocked yes)
			(layer "F.Fab")
			(hide yes)
			(effects
				(font
					(size 1.016 1.016)
					(thickness 0.1524)
				)
			)
		)
		(duplicate_pad_numbers_are_jumpers no)
		(fp_line
			(start 0.635 0)
			(end -0.635 0)
			(stroke
				(width 0.508)
				(type default)
			)
			(layer "F.SilkS")
		)
		(fp_rect
			(start -0.9652 1.778)
			(end 0.9652 -1.778)
			(stroke
				(width 0)
				(type default)
			)
			(fill no)
			(layer "F.CrtYd")
		)
		(fp_poly
			(pts
				(xy -0.9652 -1.778) (xy 0.9652 -1.778) (xy 0.9652 1.778) (xy -0.9652 1.778)
			)
			(stroke
				(width 0)
				(type default)
			)
			(fill no)
			(layer "F.Fab")
		)
		(pad "1" smd rect
			(at 0 -0.9652 180)
			(size 1.397 1.143)
			(layers "F.Cu" "F.Mask" "F.Paste")
			(net "P12V_HDD6")
		)
		(pad "2" smd rect
			(at 0 0.9652 180)
			(size 1.397 1.143)
			(layers "F.Cu" "F.Mask" "F.Paste")
			(net "GND")
		)
	)
	(footprint ""
		(layer "F.Cu")
		(at 447.834512 -245.219474 -90)
		(property "Reference" "C158"
			(at 0 0 270)
			(layer "F.SilkS")
			(hide yes)
			(effects
				(font
					(size 1.27 1.27)
				)
			)
		)
		(property "Value" "SCD01U16V1KX-GP"
			(at -2.8321 -1.7399 270)
			(unlocked yes)
			(layer "F.Fab")
			(hide yes)
			(effects
				(font
					(size 1.016 1.016)
					(thickness 0.1524)
				)
			)
		)
		(property "Device Type" "C0201H13"
			(at -2.8321 -3.2639 270)
			(unlocked yes)
			(layer "F.Fab")
			(hide yes)
			(effects
				(font
					(size 1.016 1.016)
					(thickness 0.1524)
				)
			)
		)
		(duplicate_pad_numbers_are_jumpers no)
		(fp_rect
			(start -0.2794 0.6477)
			(end 0.2794 -0.6477)
			(stroke
				(width 0)
				(type default)
			)
			(fill no)
			(layer "F.CrtYd")
		)
		(fp_rect
			(start -0.2794 0.6477)
			(end 0.2794 -0.6477)
			(stroke
				(width 0)
				(type default)
			)
			(fill no)
			(layer "F.Fab")
		)
		(pad "1" smd custom
			(at 0 -0.2794 270)
			(size 0.0762 0.0762)
			(layers "F.Cu" "F.Mask" "F.Paste")
			(net "SAS_HDD_RX_N10")
			(options
				(clearance outline)
				(anchor circle)
			)
			(primitives
				(gr_poly
					(pts
						(arc
							(start 0.1524 -0.127)
							(mid 0.137521 -0.162921)
							(end 0.1016 -0.1778)
						)
						(arc
							(start -0.1016 -0.1778)
							(mid -0.137521 -0.162921)
							(end -0.1524 -0.127)
						)
						(arc
							(start -0.1524 0.127)
							(mid -0.137521 0.162921)
							(end -0.1016 0.1778)
						)
						(arc
							(start 0.1016 0.1778)
							(mid 0.137521 0.162921)
							(end 0.1524 0.127)
						)
					)
					(width 0)
					(fill yes)
				)
			)
		)
		(pad "2" smd custom
			(at 0 0.2794 270)
			(size 0.0762 0.0762)
			(layers "F.Cu" "F.Mask" "F.Paste")
			(net "PHY_SCC_B_TO_DRV_B_10_DN")
			(options
				(clearance outline)
				(anchor circle)
			)
			(primitives
				(gr_poly
					(pts
						(arc
							(start 0.1524 -0.127)
							(mid 0.137521 -0.162921)
							(end 0.1016 -0.1778)
						)
						(arc
							(start -0.1016 -0.1778)
							(mid -0.137521 -0.162921)
							(end -0.1524 -0.127)
						)
						(arc
							(start -0.1524 0.127)
							(mid -0.137521 0.162921)
							(end -0.1016 0.1778)
						)
						(arc
							(start 0.1016 0.1778)
							(mid 0.137521 0.162921)
							(end 0.1524 0.127)
						)
					)
					(width 0)
					(fill yes)
				)
			)
		)
	)
)
